# S9S_MB_2U (Grand Teton) — schematic netlist excerpt (pin names and nets, part order shuffled) for the footprints in the layout excerpt that follows; sources: Cadence DE-HDL packaged netlist, KiCad conversion of 03242023_DA0F0TMBIJ0_F0T_Motherboard_J_brd_V01_OCP.brd

J12  SCONN288_ADR50017P087CC  SCONN288_ADR50017-P087CC IO  pkg DDR288S_1-1VXB  page 93
  VIN_BULK0  = P12V_S3_AUX_CPU0_NVDIMM
  RFU0  = TP_CHF_CPU0_DIMM2_FRU_0
  VIN_MGMT  = P3V3_AUX
  HSCL  = I3C_SPD_DDREFGH_CPU0_LVC1_SCL_3
  HSDA  = I3C_SPD_DDREFGH_CPU0_LVC1_SDA
  VSS0  = GND
  DQ0_A  = M_F_CPU0_SA_DQ<0>
  VSS1  = GND
  DQ1_A  = M_F_CPU0_SA_DQ<1>
  VSS2  = GND
  DQS0_A_T  = M_F_CPU0_SA_DQS_DP<0>
  DQS0_A_C  = M_F_CPU0_SA_DQS_DN<0>
  VSS3  = GND
  DQ4_A  = M_F_CPU0_SA_DQ<4>
  VSS4  = GND
  DQ5_A  = M_F_CPU0_SA_DQ<5>
  VSS5  = GND
  DQ8_A  = M_F_CPU0_SA_DQ<8>
  VSS6  = GND
  DQ9_A  = M_F_CPU0_SA_DQ<9>
  VSS7  = GND
  DQS1_A_T  = M_F_CPU0_SA_DQS_DP<1>
  DQS1_A_C  = M_F_CPU0_SA_DQS_DN<1>
  VSS8  = GND
  DQ12_A  = M_F_CPU0_SA_DQ<12>
  VSS9  = GND
  DQ13_A  = M_F_CPU0_SA_DQ<13>
  VSS10  = GND
  DQ16_A  = M_F_CPU0_SA_DQ<16>
  VSS11  = GND
  DQ17_A  = M_F_CPU0_SA_DQ<17>
  VSS12  = GND
  DQS2_A_T  = M_F_CPU0_SA_DQS_DP<2>
  DQS2_A_C  = M_F_CPU0_SA_DQS_DN<2>
  VSS13  = GND
  DQ20_A  = M_F_CPU0_SA_DQ<20>
  VSS14  = GND
  DQ21_A  = M_F_CPU0_SA_DQ<21>
  VSS15  = GND
  DQ24_A  = M_F_CPU0_SA_DQ<24>
  VSS16  = GND
  DQ25_A  = M_F_CPU0_SA_DQ<25>
  VSS17  = GND
  DQS3_A_T  = M_F_CPU0_SA_DQS_DP<3>
  DQS3_A_C  = M_F_CPU0_SA_DQS_DN<3>
  VSS18  = GND
  DQ28_A  = M_F_CPU0_SA_DQ<28>
  VSS19  = GND
  DQ29_A  = M_F_CPU0_SA_DQ<29>
  VSS20  = GND
  CB0_A  = M_F_CPU0_SA_CB<0>
  VSS21  = GND
  CB1_A  = M_F_CPU0_SA_CB<1>
  VSS22  = GND
  DQS4_A_T  = M_F_CPU0_SA_DQS_DP<4>
  DQS4_A_C  = M_F_CPU0_SA_DQS_DN<4>
  VSS23  = GND
  CB4_A  = M_F_CPU0_SA_CB<4>
  VSS24  = GND
  CB5_A  = M_F_CPU0_SA_CB<5>
  VSS25  = GND
  ALERT_N  = M_F_CPU0_ALERT_N
  VSS26  = GND
  CS0_A_N  = M_F_CPU0_SA_CS_N<2>
  VSS27  = GND
  CA0_A  = M_F_CPU0_SA_CA<0>
  VSS28  = GND
  CA2_A  = M_F_CPU0_SA_CA<2>
  VSS29  = GND
  CA4_A  = M_F_CPU0_SA_CA<4>
  VSS30  = GND
  CA6_A  = M_F_CPU0_SA_CA<6>
  VSS31  = GND
  PAR_A  = M_F_CPU0_SA_PAR
  VSS32  = GND
  CA0_B  = M_F_CPU0_SB_CA<0>
  VSS33  = GND
  CA2_B  = M_F_CPU0_SB_CA<2>
  VSS34  = GND
  CA4_B  = M_F_CPU0_SB_CA<4>
  VSS35  = GND
  CA6_B  = M_F_CPU0_SB_CA<6>
  VSS36  = GND
  CS0_B_N  = M_F_CPU0_SB_CS_N<2>
  VSS37  = GND
  \lbd||rsp_a_n\  = M_F_CPU0_SA_RSP<1>
  \lbs||rsp_b_n\  = M_F_CPU0_SB_RSP<1>
  VSS38  = GND
  CB4_B  = M_F_CPU0_SB_CB<4>
  VSS39  = GND
  CB5_B  = M_F_CPU0_SB_CB<5>
  VSS40  = GND
  \dqs9_b_t||tdqs9_b_t||dbi4_b_n\  = M_F_CPU0_SB_DQS_DP<9>
  \dqs9_b_c||tdqs9_b_c\  = M_F_CPU0_SB_DQS_DN<9>
  VSS41  = GND
  CB0_B  = M_F_CPU0_SB_CB<0>
  VSS42  = GND
  CB1_B  = M_F_CPU0_SB_CB<1>
  VSS43  = GND
  DQ0_B  = M_F_CPU0_SB_DQ<0>
  VSS44  = GND
  DQ1_B  = M_F_CPU0_SB_DQ<1>
  VSS45  = GND
  DQS0_B_T  = M_F_CPU0_SB_DQS_DP<0>
  DQS0_B_C  = M_F_CPU0_SB_DQS_DN<0>
  VSS46  = GND
  DQ4_B  = M_F_CPU0_SB_DQ<4>
  VSS47  = GND
  DQ5_B  = M_F_CPU0_SB_DQ<5>
  VSS48  = GND
  DQ8_B  = M_F_CPU0_SB_DQ<8>
  VSS49  = GND
  DQ9_B  = M_F_CPU0_SB_DQ<9>
  VSS50  = GND
  DQS1_B_T  = M_F_CPU0_SB_DQS_DP<1>
  DQS1_B_C  = M_F_CPU0_SB_DQS_DN<1>
  VSS51  = GND
  DQ12_B  = M_F_CPU0_SB_DQ<12>
  VSS52  = GND
  DQ13_B  = M_F_CPU0_SB_DQ<13>
  VSS53  = GND
  DQ16_B  = M_F_CPU0_SB_DQ<16>
  VSS54  = GND
  DQ17_B  = M_F_CPU0_SB_DQ<17>
  VSS55  = GND
  DQS2_B_T  = M_F_CPU0_SB_DQS_DP<2>
  DQS2_B_C  = M_F_CPU0_SB_DQS_DN<2>
  VSS56  = GND
  DQ20_B  = M_F_CPU0_SB_DQ<20>
  VSS57  = GND
  DQ21_B  = M_F_CPU0_SB_DQ<21>
  VSS58  = GND
  DQ24_B  = M_F_CPU0_SB_DQ<24>
  VSS59  = GND
  DQ25_B  = M_F_CPU0_SB_DQ<25>
  VSS60  = GND
  DQS3_B_T  = M_F_CPU0_SB_DQS_DP<3>
  DQS3_B_C  = M_F_CPU0_SB_DQS_DN<3>
  VSS61  = GND
  DQ28_B  = M_F_CPU0_SB_DQ<28>
  VSS62  = GND
  DQ29_B  = M_F_CPU0_SB_DQ<29>
  VSS63  = GND
  RFU1  = TP_CHF_CPU0_DIMM2_FRU_1
  VIN_BULK1  = P12V_S3_AUX_CPU0_NVDIMM
  VIN_BULK2  = P12V_S3_AUX_CPU0_NVDIMM
  \pwr_good||fail_n\  = PWRGD_CHF_CPU0_DIMM2
  HSA  = PD_CHF_CPU0_DIMM2_SAA
  RFU2  = TP_CHF_CPU0_DIMM2_FRU_2
  RFU3  = TP_CHF_CPU0_DIMM2_FRU_3
  VSS64  = GND
  DQ2_A  = M_F_CPU0_SA_DQ<2>
  VSS65  = GND
  DQ3_A  = M_F_CPU0_SA_DQ<3>
  VSS66  = GND
  \dqs5_a_c||tdqs5_a_c||dqs5_a_t||tdqs5_a_t\  = M_F_CPU0_SA_DQS_DN<5>
  \dqs5_a_t||tdqs5_a_t\  = M_F_CPU0_SA_DQS_DP<5>
  VSS67  = GND
  DQ6_A  = M_F_CPU0_SA_DQ<6>
  VSS68  = GND
  DQ7_A  = M_F_CPU0_SA_DQ<7>
  VSS69  = GND
  DQ10_A  = M_F_CPU0_SA_DQ<10>
  VSS70  = GND
  DQ11_A  = M_F_CPU0_SA_DQ<11>
  VSS71  = GND
  \dqs6_a_c||tdqs6_a_c||dqs6_a_t||tdqs6_a_t\  = M_F_CPU0_SA_DQS_DN<6>
  \dqs6_a_t||tdqs6_a_t\  = M_F_CPU0_SA_DQS_DP<6>
  VSS72  = GND
  DQ14_A  = M_F_CPU0_SA_DQ<14>
  VSS73  = GND
  DQ15_A  = M_F_CPU0_SA_DQ<15>
  VSS74  = GND
  DQ18_A  = M_F_CPU0_SA_DQ<18>
  VSS75  = GND
  DQ19_A  = M_F_CPU0_SA_DQ<19>
  VSS76  = GND
  \dqs7_a_c||tdqs7_a_c\  = M_F_CPU0_SA_DQS_DN<7>
  \dqs7_a_t||tdqs7_a_t\  = M_F_CPU0_SA_DQS_DP<7>
  VSS77  = GND
  DQ22_A  = M_F_CPU0_SA_DQ<22>
  VSS78  = GND
  DQ23_A  = M_F_CPU0_SA_DQ<23>
  VSS79  = GND
  DQ26_A  = M_F_CPU0_SA_DQ<26>
  VSS80  = GND
  DQ27_A  = M_F_CPU0_SA_DQ<27>
  VSS81  = GND
  \dqs8_a_c||tdqs8_a_c\  = M_F_CPU0_SA_DQS_DN<8>
  \dqs8_a_t||tdqs8_a_t\  = M_F_CPU0_SA_DQS_DP<8>
  VSS82  = GND
  DQ30_A  = M_F_CPU0_SA_DQ<30>
  VSS83  = GND
  DQ31_A  = M_F_CPU0_SA_DQ<31>
  VSS84  = GND
  CB2_A  = M_F_CPU0_SA_CB<2>
  VSS85  = GND
  CB3_A  = M_F_CPU0_SA_CB<3>
  VSS86  = GND
  \dqs9_a_c||tdqs9_a_c\  = M_F_CPU0_SA_DQS_DN<9>
  \dqs9_a_t||tdqs9_a_t\  = M_F_CPU0_SA_DQS_DP<9>
  VSS87  = GND
  CB6_A  = M_F_CPU0_SA_CB<6>
  VSS88  = GND
  CB7_A  = M_F_CPU0_SA_CB<7>
  VSS89  = GND
  RESET_N  = RST_M_EF_CPU0_FPGA_N
  VSS90  = GND
  CS1_A_N  = M_F_CPU0_SA_CS_N<3>
  VSS91  = GND
  CA1_A  = M_F_CPU0_SA_CA<1>
  VSS92  = GND
  CA3_A  = M_F_CPU0_SA_CA<3>
  VSS93  = GND
  CA5_A  = M_F_CPU0_SA_CA<5>
  VSS94  = GND
  CK_T  = M_F_CPU0_CLK_DP<1>
  CK_C  = M_F_CPU0_CLK_DN<1>
  VSS95  = GND
  RFU4  = TP_CHF_CPU0_DIMM2_FRU_4
  CA1_B  = M_F_CPU0_SB_CA<1>
  VSS96  = GND
  CA3_B  = M_F_CPU0_SB_CA<3>
  VSS97  = GND
  CA5_B  = M_F_CPU0_SB_CA<5>
  VSS98  = GND
  PAR_B  = M_F_CPU0_SB_PAR
  VSS99  = GND
  CS1_B_N  = M_F_CPU0_SB_CS_N<3>
  VSS100  = GND
  RFU5  = TP_CHF_CPU0_DIMM2_FRU_5
  RFU6  = TP_CHF_CPU0_DIMM2_FRU_6
  VSS101  = GND
  CB6_B  = M_F_CPU0_SB_CB<6>
  VSS102  = GND
  CB7_B  = M_F_CPU0_SB_CB<7>
  VSS103  = GND
  DQS4_B_C  = M_F_CPU0_SB_DQS_DN<4>
  DQS4_B_T  = M_F_CPU0_SB_DQS_DP<4>
  VSS104  = GND
  CB2_B  = M_F_CPU0_SB_CB<2>
  VSS105  = GND
  CB3_B  = M_F_CPU0_SB_CB<3>
  VSS106  = GND
  DQ2_B  = M_F_CPU0_SB_DQ<2>
  VSS107  = GND
  DQ3_B  = M_F_CPU0_SB_DQ<3>
  VSS108  = GND
  \dqs5_b_c||tdqs5_b_c\  = M_F_CPU0_SB_DQS_DN<5>
  \dqs5_b_t||tdqs5_b_t\  = M_F_CPU0_SB_DQS_DP<5>
  VSS109  = GND
  DQ6_B  = M_F_CPU0_SB_DQ<6>
  VSS110  = GND
  DQ7_B  = M_F_CPU0_SB_DQ<7>
  VSS111  = GND
  DQ10_B  = M_F_CPU0_SB_DQ<10>
  VSS112  = GND
  DQ11_B  = M_F_CPU0_SB_DQ<11>
  VSS113  = GND
  \dqs6_b_c||tdqs6_b_c\  = M_F_CPU0_SB_DQS_DN<6>
  \dqs6_b_t||tdqs6_b_t\  = M_F_CPU0_SB_DQS_DP<6>
  VSS114  = GND
  DQ14_B  = M_F_CPU0_SB_DQ<14>
  VSS115  = GND
  DQ15_B  = M_F_CPU0_SB_DQ<15>
  VSS116  = GND
  DQ18_B  = M_F_CPU0_SB_DQ<18>
  VSS117  = GND
  DQ19_B  = M_F_CPU0_SB_DQ<19>
  VSS118  = GND
  \dqs7_b_c||tdqs7_b_c\  = M_F_CPU0_SB_DQS_DN<7>
  \dqs7_b_t||tdqs7_b_t\  = M_F_CPU0_SB_DQS_DP<7>
  VSS119  = GND
  DQ22_B  = M_F_CPU0_SB_DQ<22>
  VSS120  = GND
  DQ23_B  = M_F_CPU0_SB_DQ<23>
  VSS121  = GND
  DQ26_B  = M_F_CPU0_SB_DQ<26>
  VSS122  = GND
  DQ27_B  = M_F_CPU0_SB_DQ<27>
  VSS123  = GND
  \dqs8_b_c||tdqs8_b_c\  = M_F_CPU0_SB_DQS_DN<8>
  \dqs8_b_t||tdqs8_b_t\  = M_F_CPU0_SB_DQS_DP<8>
  VSS124  = GND
  DQ30_B  = M_F_CPU0_SB_DQ<30>
  VSS125  = GND
  DQ31_B  = M_F_CPU0_SB_DQ<31>
  VSS126  = GND
  G1  = GND
  G2  = GND
  G3  = GND

(kicad_pcb
	(version 20260206)
	(generator "pcbnew")
	(generator_version "10.0")
	(general
		(thickness 1.6)
		(legacy_teardrops no)
	)
	(paper "A4")
	(title_block
		(title "03242023_DA0F0TMBIJ0_F0T_Motherboard_J_brd_V01_OCP.brd")
		(comment 1 "Grand Teton / footprint 3198 of 6105 (J12), pads 183-228 of 291")
	)
	(layers
		(0 "F.Cu" signal "TOP")
		(4 "In1.Cu" signal "GND")
		(6 "In2.Cu" signal "IN1")
		(8 "In3.Cu" signal "GND1")
		(10 "In4.Cu" signal "IN2")
		(12 "In5.Cu" signal "GND2")
		(14 "In6.Cu" signal "IN3")
		(16 "In7.Cu" signal "GND3")
		(18 "In8.Cu" signal "VCC")
		(20 "In9.Cu" signal "VCC1")
		(22 "In10.Cu" signal "GND4")
		(24 "In11.Cu" signal "IN4")
		(26 "In12.Cu" signal "GND5")
		(28 "In13.Cu" signal "IN5")
		(30 "In14.Cu" signal "GND6")
		(32 "In15.Cu" signal "IN6")
		(34 "In16.Cu" signal "GND7")
		(2 "B.Cu" signal "BOTTOM")
		(9 "F.Adhes" user "F.Adhesive")
		(11 "B.Adhes" user "B.Adhesive")
		(13 "F.Paste" user "Package Geometry/Pastemask Top")
		(15 "B.Paste" user "Package Geometry/Pastemask Bottom")
		(5 "F.SilkS" user "Ref Des/Silkscreen Top")
		(7 "B.SilkS" user "Ref Des/Silkscreen Bottom")
		(1 "F.Mask" user "Board Geometry/Soldermask Top")
		(3 "B.Mask" user "Board Geometry/Soldermask Bottom")
		(17 "Dwgs.User" user "User.Drawings")
		(19 "Cmts.User" user "User.Comments")
		(21 "Eco1.User" user "User.Eco1")
		(23 "Eco2.User" user "User.Eco2")
		(25 "Edge.Cuts" user "Board Geometry/Outline")
		(27 "Margin" user)
		(31 "F.CrtYd" user "Package Geometry/Place Bound Top")
		(29 "B.CrtYd" user "Package Geometry/Place Bound Bottom")
		(35 "F.Fab" user "Ref Des/Assembly Top")
		(33 "B.Fab" user "Ref Des/Assembly Bottom")
	)
	(footprint ""
		(layer "F.Cu")
		(at 423.890948 -258.091686)
		(property "Reference" "J12"
			(at -3.683 -81.702148 0)
			(unlocked yes)
			(layer "F.SilkS")
			(effects
				(font
					(size 0.7874 0.5842)
					(thickness 0.1524)
				)
				(justify left)
			)
		)
		(property "Value" ""
			(at 0 0 0)
			(layer "F.Fab")
			(effects
				(font
					(size 1.27 1.27)
				)
			)
		)
		(duplicate_pad_numbers_are_jumpers no)
		(pad "183" smd rect
			(at 2.050034 -31.025084 270)
			(size 0.519938 1.4986)
			(layers "F.Cu" "F.Mask" "F.Paste")
			(net "M_F_CPU0_SA_DQ<23>")
		)
		(pad "184" smd rect
			(at 2.050034 -30.174946 270)
			(size 0.519938 1.4986)
			(layers "F.Cu" "F.Mask" "F.Paste")
			(net "GND")
		)
		(pad "185" smd rect
			(at 2.050034 -29.325062 270)
			(size 0.519938 1.4986)
			(layers "F.Cu" "F.Mask" "F.Paste")
			(net "M_F_CPU0_SA_DQ<26>")
		)
		(pad "186" smd rect
			(at 2.050034 -28.474924 270)
			(size 0.519938 1.4986)
			(layers "F.Cu" "F.Mask" "F.Paste")
			(net "GND")
		)
		(pad "187" smd rect
			(at 2.050034 -27.62504 270)
			(size 0.519938 1.4986)
			(layers "F.Cu" "F.Mask" "F.Paste")
			(net "M_F_CPU0_SA_DQ<27>")
		)
		(pad "188" smd rect
			(at 2.050034 -26.774902 270)
			(size 0.519938 1.4986)
			(layers "F.Cu" "F.Mask" "F.Paste")
			(net "GND")
		)
		(pad "189" smd rect
			(at 2.050034 -25.925018 270)
			(size 0.519938 1.4986)
			(layers "F.Cu" "F.Mask" "F.Paste")
			(net "M_F_CPU0_SA_DQS_DN<8>")
		)
		(pad "190" smd rect
			(at 2.050034 -25.07488 270)
			(size 0.519938 1.4986)
			(layers "F.Cu" "F.Mask" "F.Paste")
			(net "M_F_CPU0_SA_DQS_DP<8>")
		)
		(pad "191" smd rect
			(at 2.050034 -24.224996 270)
			(size 0.519938 1.4986)
			(layers "F.Cu" "F.Mask" "F.Paste")
			(net "GND")
		)
		(pad "192" smd rect
			(at 2.050034 -23.375112 270)
			(size 0.519938 1.4986)
			(layers "F.Cu" "F.Mask" "F.Paste")
			(net "M_F_CPU0_SA_DQ<30>")
		)
		(pad "193" smd rect
			(at 2.050034 -22.524974 270)
			(size 0.519938 1.4986)
			(layers "F.Cu" "F.Mask" "F.Paste")
			(net "GND")
		)
		(pad "194" smd rect
			(at 2.050034 -21.67509 270)
			(size 0.519938 1.4986)
			(layers "F.Cu" "F.Mask" "F.Paste")
			(net "M_F_CPU0_SA_DQ<31>")
		)
		(pad "195" smd rect
			(at 2.050034 -20.824952 270)
			(size 0.519938 1.4986)
			(layers "F.Cu" "F.Mask" "F.Paste")
			(net "GND")
		)
		(pad "196" smd rect
			(at 2.050034 -19.975068 270)
			(size 0.519938 1.4986)
			(layers "F.Cu" "F.Mask" "F.Paste")
			(net "M_F_CPU0_SA_CB<2>")
		)
		(pad "197" smd rect
			(at 2.050034 -19.12493 270)
			(size 0.519938 1.4986)
			(layers "F.Cu" "F.Mask" "F.Paste")
			(net "GND")
		)
		(pad "198" smd rect
			(at 2.050034 -18.275046 270)
			(size 0.519938 1.4986)
			(layers "F.Cu" "F.Mask" "F.Paste")
			(net "M_F_CPU0_SA_CB<3>")
		)
		(pad "199" smd rect
			(at 2.050034 -17.424908 270)
			(size 0.519938 1.4986)
			(layers "F.Cu" "F.Mask" "F.Paste")
			(net "GND")
		)
		(pad "200" smd rect
			(at 2.050034 -16.575024 270)
			(size 0.519938 1.4986)
			(layers "F.Cu" "F.Mask" "F.Paste")
			(net "M_F_CPU0_SA_DQS_DN<9>")
		)
		(pad "201" smd rect
			(at 2.050034 -15.724886 270)
			(size 0.519938 1.4986)
			(layers "F.Cu" "F.Mask" "F.Paste")
			(net "M_F_CPU0_SA_DQS_DP<9>")
		)
		(pad "202" smd rect
			(at 2.050034 -14.875002 270)
			(size 0.519938 1.4986)
			(layers "F.Cu" "F.Mask" "F.Paste")
			(net "GND")
		)
		(pad "203" smd rect
			(at 2.050034 -14.025118 270)
			(size 0.519938 1.4986)
			(layers "F.Cu" "F.Mask" "F.Paste")
			(net "M_F_CPU0_SA_CB<6>")
		)
		(pad "204" smd rect
			(at 2.050034 -13.17498 270)
			(size 0.519938 1.4986)
			(layers "F.Cu" "F.Mask" "F.Paste")
			(net "GND")
		)
		(pad "205" smd rect
			(at 2.050034 -12.325096 270)
			(size 0.519938 1.4986)
			(layers "F.Cu" "F.Mask" "F.Paste")
			(net "M_F_CPU0_SA_CB<7>")
		)
		(pad "206" smd rect
			(at 2.050034 -11.474958 270)
			(size 0.519938 1.4986)
			(layers "F.Cu" "F.Mask" "F.Paste")
			(net "GND")
		)
		(pad "207" smd rect
			(at 2.050034 -10.625074 270)
			(size 0.519938 1.4986)
			(layers "F.Cu" "F.Mask" "F.Paste")
			(net "RST_M_EF_CPU0_FPGA_N")
		)
		(pad "208" smd rect
			(at 2.050034 -9.774936 270)
			(size 0.519938 1.4986)
			(layers "F.Cu" "F.Mask" "F.Paste")
			(net "GND")
		)
		(pad "209" smd rect
			(at 2.050034 -8.925052 270)
			(size 0.519938 1.4986)
			(layers "F.Cu" "F.Mask" "F.Paste")
			(net "M_F_CPU0_SA_CS_N<3>")
		)
		(pad "210" smd rect
			(at 2.050034 -8.074914 270)
			(size 0.519938 1.4986)
			(layers "F.Cu" "F.Mask" "F.Paste")
			(net "GND")
		)
		(pad "211" smd rect
			(at 2.050034 -7.22503 270)
			(size 0.519938 1.4986)
			(layers "F.Cu" "F.Mask" "F.Paste")
			(net "M_F_CPU0_SA_CA<1>")
		)
		(pad "212" smd rect
			(at 2.050034 -6.374892 270)
			(size 0.519938 1.4986)
			(layers "F.Cu" "F.Mask" "F.Paste")
			(net "GND")
		)
		(pad "213" smd rect
			(at 2.050034 -5.525008 270)
			(size 0.519938 1.4986)
			(layers "F.Cu" "F.Mask" "F.Paste")
			(net "M_F_CPU0_SA_CA<3>")
		)
		(pad "214" smd rect
			(at 2.050034 -4.675124 270)
			(size 0.519938 1.4986)
			(layers "F.Cu" "F.Mask" "F.Paste")
			(net "GND")
		)
		(pad "215" smd rect
			(at 2.050034 -3.824986 270)
			(size 0.519938 1.4986)
			(layers "F.Cu" "F.Mask" "F.Paste")
			(net "M_F_CPU0_SA_CA<5>")
		)
		(pad "216" smd rect
			(at 2.050034 -2.975102 270)
			(size 0.519938 1.4986)
			(layers "F.Cu" "F.Mask" "F.Paste")
			(net "GND")
		)
		(pad "217" smd rect
			(at 2.050034 -2.124964 270)
			(size 0.519938 1.4986)
			(layers "F.Cu" "F.Mask" "F.Paste")
			(net "M_F_CPU0_CLK_DP<1>")
		)
		(pad "218" smd rect
			(at 2.050034 -1.27508 270)
			(size 0.519938 1.4986)
			(layers "F.Cu" "F.Mask" "F.Paste")
			(net "M_F_CPU0_CLK_DN<1>")
		)
		(pad "219" smd rect
			(at 2.050034 -0.424942 270)
			(size 0.519938 1.4986)
			(layers "F.Cu" "F.Mask" "F.Paste")
			(net "GND")
		)
		(pad "220" smd rect
			(at 2.050034 5.525008 270)
			(size 0.519938 1.4986)
			(layers "F.Cu" "F.Mask" "F.Paste")
			(net "TP_CHF_CPU0_DIMM2_FRU_4")
		)
		(pad "221" smd rect
			(at 2.050034 6.374892 270)
			(size 0.519938 1.4986)
			(layers "F.Cu" "F.Mask" "F.Paste")
			(net "M_F_CPU0_SB_CA<1>")
		)
		(pad "222" smd rect
			(at 2.050034 7.22503 270)
			(size 0.519938 1.4986)
			(layers "F.Cu" "F.Mask" "F.Paste")
			(net "GND")
		)
		(pad "223" smd rect
			(at 2.050034 8.074914 270)
			(size 0.519938 1.4986)
			(layers "F.Cu" "F.Mask" "F.Paste")
			(net "M_F_CPU0_SB_CA<3>")
		)
		(pad "224" smd rect
			(at 2.050034 8.925052 270)
			(size 0.519938 1.4986)
			(layers "F.Cu" "F.Mask" "F.Paste")
			(net "GND")
		)
		(pad "225" smd rect
			(at 2.050034 9.774936 270)
			(size 0.519938 1.4986)
			(layers "F.Cu" "F.Mask" "F.Paste")
			(net "M_F_CPU0_SB_CA<5>")
		)
		(pad "226" smd rect
			(at 2.050034 10.625074 270)
			(size 0.519938 1.4986)
			(layers "F.Cu" "F.Mask" "F.Paste")
			(net "GND")
		)
		(pad "227" smd rect
			(at 2.050034 11.474958 270)
			(size 0.519938 1.4986)
			(layers "F.Cu" "F.Mask" "F.Paste")
			(net "M_F_CPU0_SB_PAR")
		)
		(pad "228" smd rect
			(at 2.050034 12.325096 270)
			(size 0.519938 1.4986)
			(layers "F.Cu" "F.Mask" "F.Paste")
			(net "GND")
		)
	)
)
